(kicad_pcb
	(version 20260206)
	(generator "pcbnew")
	(generator_version "10.0")
	(general
		(thickness 1.6)
		(legacy_teardrops no)
	)
	(paper "A4")
	(title_block
		(title "pdpb — Lightning_PDPB_BRD.brd")
		(comment 1 "Lightning (Wiwynn / Facebook NVMe JBOF) / footprints 284-290 of 1140")
	)
	(layers
		(0 "F.Cu" signal "TOP")
		(4 "In1.Cu" signal "L2GND")
		(6 "In2.Cu" signal "L3")
		(8 "In3.Cu" signal "L4VCC")
		(10 "In4.Cu" signal "L5VCC")
		(12 "In5.Cu" signal "L6")
		(14 "In6.Cu" signal "L7GND")
		(2 "B.Cu" signal "BOTTOM")
		(9 "F.Adhes" user "F.Adhesive")
		(11 "B.Adhes" user "B.Adhesive")
		(13 "F.Paste" user "Package Geometry/Pastemask Top")
		(15 "B.Paste" user "Package Geometry/Pastemask Bottom")
		(5 "F.SilkS" user "Ref Des/Silkscreen Top")
		(7 "B.SilkS" user "Ref Des/Silkscreen Bottom")
		(1 "F.Mask" user "Board Geometry/Soldermask Top")
		(3 "B.Mask" user "Board Geometry/Soldermask Bottom")
		(17 "Dwgs.User" user "User.Drawings")
		(19 "Cmts.User" user "User.Comments")
		(21 "Eco1.User" user "User.Eco1")
		(23 "Eco2.User" user "User.Eco2")
		(25 "Edge.Cuts" user "Board Geometry/Outline")
		(27 "Margin" user)
		(31 "F.CrtYd" user "Package Geometry/Place Bound Top")
		(29 "B.CrtYd" user "Package Geometry/Place Bound Bottom")
		(35 "F.Fab" user "Ref Des/Assembly Top")
		(33 "B.Fab" user "Ref Des/Assembly Bottom")
	)
	(footprint ""
		(layer "F.Cu")
		(at 27.5336 -105.3592)
		(property "Reference" "PC1212"
			(at 0 0 0)
			(layer "F.SilkS")
			(hide yes)
			(effects
				(font
					(size 1.27 1.27)
				)
			)
		)
		(property "Value" "SCD1U50V3KX-GP"
			(at 0 -2.8194 0)
			(unlocked yes)
			(layer "F.Fab")
			(hide yes)
			(effects
				(font
					(size 1.016 1.016)
					(thickness 0.1524)
				)
			)
		)
		(property "Device Type" "C603H36"
			(at 0 -4.3434 0)
			(unlocked yes)
			(layer "F.Fab")
			(hide yes)
			(effects
				(font
					(size 1.016 1.016)
					(thickness 0.1524)
				)
			)
		)
		(duplicate_pad_numbers_are_jumpers no)
		(fp_line
			(start 0.508 0)
			(end -0.508 0)
			(stroke
				(width 0.2032)
				(type default)
			)
			(layer "F.SilkS")
		)
		(fp_rect
			(start -0.5842 1.3335)
			(end 0.5842 -1.3335)
			(stroke
				(width 0)
				(type default)
			)
			(fill no)
			(layer "F.CrtYd")
		)
		(fp_rect
			(start -0.5842 1.3335)
			(end 0.5842 -1.3335)
			(stroke
				(width 0)
				(type default)
			)
			(fill no)
			(layer "F.Fab")
		)
		(pad "1" smd custom
			(at 0 -0.762)
			(size 0.2159 0.2159)
			(layers "F.Cu" "F.Mask" "F.Paste")
			(net "P12V_SSD13")
			(options
				(clearance outline)
				(anchor circle)
			)
			(primitives
				(gr_poly
					(pts
						(arc
							(start -0.3302 -0.4318)
							(mid -0.402042 -0.402042)
							(end -0.4318 -0.3302)
						)
						(arc
							(start -0.4318 0.3302)
							(mid -0.402042 0.402042)
							(end -0.3302 0.4318)
						)
						(arc
							(start 0.3302 0.4318)
							(mid 0.402042 0.402042)
							(end 0.4318 0.3302)
						)
						(arc
							(start 0.4318 -0.3302)
							(mid 0.402042 -0.402042)
							(end 0.3302 -0.4318)
						)
					)
					(width 0)
					(fill yes)
				)
			)
		)
		(pad "2" smd custom
			(at 0 0.762)
			(size 0.2159 0.2159)
			(layers "F.Cu" "F.Mask" "F.Paste")
			(net "GND")
			(options
				(clearance outline)
				(anchor circle)
			)
			(primitives
				(gr_poly
					(pts
						(arc
							(start -0.3302 -0.4318)
							(mid -0.402042 -0.402042)
							(end -0.4318 -0.3302)
						)
						(arc
							(start -0.4318 0.3302)
							(mid -0.402042 0.402042)
							(end -0.3302 0.4318)
						)
						(arc
							(start 0.3302 0.4318)
							(mid 0.402042 0.402042)
							(end 0.4318 0.3302)
						)
						(arc
							(start 0.4318 -0.3302)
							(mid 0.402042 -0.402042)
							(end 0.3302 -0.4318)
						)
					)
					(width 0)
					(fill yes)
				)
			)
		)
	)
	(footprint ""
		(layer "F.Cu")
		(at 208.153 -87.122)
		(property "Reference" "R555"
			(at 0 0 0)
			(layer "F.SilkS")
			(hide yes)
			(effects
				(font
					(size 1.27 1.27)
				)
			)
		)
		(property "Value" "200KR2F-L-GP"
			(at 0.064008 -3.993896 0)
			(unlocked yes)
			(layer "F.Fab")
			(hide yes)
			(effects
				(font
					(size 1.016 1.016)
					(thickness 0.1524)
				)
			)
		)
		(property "Device Type" "R402H16"
			(at 0.064008 -5.517896 0)
			(unlocked yes)
			(layer "F.Fab")
			(hide yes)
			(effects
				(font
					(size 1.016 1.016)
					(thickness 0.1524)
				)
			)
		)
		(duplicate_pad_numbers_are_jumpers no)
		(fp_line
			(start -0.508 -0.9398)
			(end -0.508 0.9398)
			(stroke
				(width 0.1524)
				(type default)
			)
			(layer "F.SilkS")
		)
		(fp_line
			(start 0.508 -0.9398)
			(end -0.508 -0.9398)
			(stroke
				(width 0.1524)
				(type default)
			)
			(layer "F.SilkS")
		)
		(fp_rect
			(start -0.508 0.9398)
			(end 0.508 -0.9398)
			(stroke
				(width 0)
				(type default)
			)
			(fill no)
			(layer "F.CrtYd")
		)
		(fp_rect
			(start -0.508 0.9398)
			(end 0.508 -0.9398)
			(stroke
				(width 0)
				(type default)
			)
			(fill no)
			(layer "F.Fab")
		)
		(pad "1" smd custom
			(at 0 -0.4445)
			(size 0.1397 0.1397)
			(layers "F.Cu" "F.Mask" "F.Paste")
			(net "SW_SSD4_R")
			(options
				(clearance outline)
				(anchor circle)
			)
			(primitives
				(gr_poly
					(pts
						(arc
							(start -0.1778 -0.2794)
							(mid -0.249642 -0.249642)
							(end -0.2794 -0.1778)
						)
						(arc
							(start -0.2794 0.1778)
							(mid -0.249642 0.249642)
							(end -0.1778 0.2794)
						)
						(arc
							(start 0.1778 0.2794)
							(mid 0.249642 0.249642)
							(end 0.2794 0.1778)
						)
						(arc
							(start 0.2794 -0.1778)
							(mid 0.249642 -0.249642)
							(end 0.1778 -0.2794)
						)
					)
					(width 0)
					(fill yes)
				)
			)
		)
		(pad "2" smd custom
			(at 0 0.4445)
			(size 0.1397 0.1397)
			(layers "F.Cu" "F.Mask" "F.Paste")
			(net "SW_SSD4_N")
			(options
				(clearance outline)
				(anchor circle)
			)
			(primitives
				(gr_poly
					(pts
						(arc
							(start -0.1778 -0.2794)
							(mid -0.249642 -0.249642)
							(end -0.2794 -0.1778)
						)
						(arc
							(start -0.2794 0.1778)
							(mid -0.249642 0.249642)
							(end -0.1778 0.2794)
						)
						(arc
							(start 0.1778 0.2794)
							(mid 0.249642 0.249642)
							(end 0.2794 0.1778)
						)
						(arc
							(start 0.2794 -0.1778)
							(mid 0.249642 -0.249642)
							(end 0.1778 -0.2794)
						)
					)
					(width 0)
					(fill yes)
				)
			)
		)
	)
	(footprint ""
		(layer "F.Cu")
		(at 52.832 -12.446 180)
		(property "Reference" "D32"
			(at 0 0 180)
			(layer "F.SilkS")
			(hide yes)
			(effects
				(font
					(size 1.27 1.27)
				)
			)
		)
		(property "Value" "RB551V30-1-GP"
			(at 0 -6.7818 180)
			(unlocked yes)
			(layer "F.Fab")
			(hide yes)
			(effects
				(font
					(size 1.016 1.016)
					(thickness 0.1524)
				)
			)
		)
		(property "Device Type" "SOD323AKH44"
			(at 0 -8.6868 180)
			(unlocked yes)
			(layer "F.Fab")
			(hide yes)
			(effects
				(font
					(size 1.016 1.016)
					(thickness 0.1524)
				)
			)
		)
		(duplicate_pad_numbers_are_jumpers no)
		(fp_line
			(start 0.889 2.159)
			(end -0.889 2.159)
			(stroke
				(width 0.1524)
				(type default)
			)
			(layer "F.SilkS")
		)
		(fp_line
			(start 0.889 -1.9304)
			(end 0.889 2.159)
			(stroke
				(width 0.1524)
				(type default)
			)
			(layer "F.SilkS")
		)
		(fp_line
			(start 0.762 2.0574)
			(end -0.762 2.0574)
			(stroke
				(width 0.508)
				(type default)
			)
			(layer "F.SilkS")
		)
		(fp_line
			(start -0.889 2.159)
			(end -0.889 -1.9304)
			(stroke
				(width 0.1524)
				(type default)
			)
			(layer "F.SilkS")
		)
		(fp_line
			(start -0.889 -1.9304)
			(end 0.889 -1.9304)
			(stroke
				(width 0.1524)
				(type default)
			)
			(layer "F.SilkS")
		)
		(fp_rect
			(start -1.016 2.3114)
			(end 1.016 -2.0066)
			(stroke
				(width 0)
				(type default)
			)
			(fill no)
			(layer "F.CrtYd")
		)
		(fp_poly
			(pts
				(xy -1.016 -2.0066) (xy 1.016 -2.0066) (xy 1.016 2.3114) (xy -1.016 2.3114)
			)
			(stroke
				(width 0)
				(type default)
			)
			(fill no)
			(layer "F.Fab")
		)
		(pad "A" smd rect
			(at 0 -1.143 180)
			(size 0.5588 1.016)
			(layers "F.Cu" "F.Mask" "F.Paste")
			(net "SW_SSD14_R")
		)
		(pad "K" smd rect
			(at 0 1.143 180)
			(size 0.5588 1.016)
			(layers "F.Cu" "F.Mask" "F.Paste")
			(net "SW_SSD14_N")
		)
	)
	(footprint ""
		(layer "F.Cu")
		(at 78.9686 -215.0618 -90)
		(property "Reference" "C8930"
			(at 0 0 270)
			(layer "F.SilkS")
			(hide yes)
			(effects
				(font
					(size 1.27 1.27)
				)
			)
		)
		(property "Value" "SC10U25V3MX-GP"
			(at 0 -2.8194 270)
			(unlocked yes)
			(layer "F.Fab")
			(hide yes)
			(effects
				(font
					(size 1.016 1.016)
					(thickness 0.1524)
				)
			)
		)
		(property "Device Type" "C603H40"
			(at 0 -4.3434 270)
			(unlocked yes)
			(layer "F.Fab")
			(hide yes)
			(effects
				(font
					(size 1.016 1.016)
					(thickness 0.1524)
				)
			)
		)
		(duplicate_pad_numbers_are_jumpers no)
		(fp_line
			(start 0.508 0)
			(end -0.508 0)
			(stroke
				(width 0.2032)
				(type default)
			)
			(layer "F.SilkS")
		)
		(fp_rect
			(start -0.5842 1.3335)
			(end 0.5842 -1.3335)
			(stroke
				(width 0)
				(type default)
			)
			(fill no)
			(layer "F.CrtYd")
		)
		(fp_rect
			(start -0.5842 1.3335)
			(end 0.5842 -1.3335)
			(stroke
				(width 0)
				(type default)
			)
			(fill no)
			(layer "F.Fab")
		)
		(pad "1" smd custom
			(at 0 -0.762 270)
			(size 0.2159 0.2159)
			(layers "F.Cu" "F.Mask" "F.Paste")
			(net "VDD_DIFF_3")
			(options
				(clearance outline)
				(anchor circle)
			)
			(primitives
				(gr_poly
					(pts
						(arc
							(start -0.3302 -0.4318)
							(mid -0.402042 -0.402042)
							(end -0.4318 -0.3302)
						)
						(arc
							(start -0.4318 0.3302)
							(mid -0.402042 0.402042)
							(end -0.3302 0.4318)
						)
						(arc
							(start 0.3302 0.4318)
							(mid 0.402042 0.402042)
							(end 0.4318 0.3302)
						)
						(arc
							(start 0.4318 -0.3302)
							(mid 0.402042 -0.402042)
							(end 0.3302 -0.4318)
						)
					)
					(width 0)
					(fill yes)
				)
			)
		)
		(pad "2" smd custom
			(at 0 0.762 270)
			(size 0.2159 0.2159)
			(layers "F.Cu" "F.Mask" "F.Paste")
			(net "GND")
			(options
				(clearance outline)
				(anchor circle)
			)
			(primitives
				(gr_poly
					(pts
						(arc
							(start -0.3302 -0.4318)
							(mid -0.402042 -0.402042)
							(end -0.4318 -0.3302)
						)
						(arc
							(start -0.4318 0.3302)
							(mid -0.402042 0.402042)
							(end -0.3302 0.4318)
						)
						(arc
							(start 0.3302 0.4318)
							(mid 0.402042 0.402042)
							(end 0.4318 0.3302)
						)
						(arc
							(start 0.4318 -0.3302)
							(mid 0.402042 -0.402042)
							(end 0.3302 -0.4318)
						)
					)
					(width 0)
					(fill yes)
				)
			)
		)
	)
	(footprint ""
		(layer "F.Cu")
		(at 232.029 -429.514 -90)
		(property "Reference" "PC1283"
			(at 0 0 270)
			(layer "F.SilkS")
			(hide yes)
			(effects
				(font
					(size 1.27 1.27)
				)
			)
		)
		(property "Value" "SC1KP50V2KX-1GP"
			(at 1.1811 -2.7051 270)
			(unlocked yes)
			(layer "F.Fab")
			(hide yes)
			(effects
				(font
					(size 1.016 1.016)
					(thickness 0.1524)
				)
			)
		)
		(property "Device Type" "C402H22"
			(at 1.1811 -4.2291 270)
			(unlocked yes)
			(layer "F.Fab")
			(hide yes)
			(effects
				(font
					(size 1.016 1.016)
					(thickness 0.1524)
				)
			)
		)
		(duplicate_pad_numbers_are_jumpers no)
		(fp_rect
			(start -0.4318 0.9525)
			(end 0.4318 -0.9525)
			(stroke
				(width 0)
				(type default)
			)
			(fill no)
			(layer "F.CrtYd")
		)
		(fp_rect
			(start -0.4318 0.9525)
			(end 0.4318 -0.9525)
			(stroke
				(width 0)
				(type default)
			)
			(fill no)
			(layer "F.Fab")
		)
		(pad "1" smd custom
			(at 0 -0.4445 270)
			(size 0.1524 0.1524)
			(layers "F.Cu" "F.Mask" "F.Paste")
			(net "P3V3_VFB_R")
			(options
				(clearance outline)
				(anchor circle)
			)
			(primitives
				(gr_poly
					(pts
						(arc
							(start 0.3048 -0.2032)
							(mid 0.275042 -0.275042)
							(end 0.2032 -0.3048)
						)
						(arc
							(start -0.2032 -0.3048)
							(mid -0.275042 -0.275042)
							(end -0.3048 -0.2032)
						)
						(arc
							(start -0.3048 0.2032)
							(mid -0.275042 0.275042)
							(end -0.2032 0.3048)
						)
						(arc
							(start 0.2032 0.3048)
							(mid 0.275042 0.275042)
							(end 0.3048 0.2032)
						)
					)
					(width 0)
					(fill yes)
				)
			)
		)
		(pad "2" smd custom
			(at 0 0.4445 270)
			(size 0.1524 0.1524)
			(layers "F.Cu" "F.Mask" "F.Paste")
			(net "P3V3_VFB")
			(options
				(clearance outline)
				(anchor circle)
			)
			(primitives
				(gr_poly
					(pts
						(arc
							(start 0.3048 -0.2032)
							(mid 0.275042 -0.275042)
							(end 0.2032 -0.3048)
						)
						(arc
							(start -0.2032 -0.3048)
							(mid -0.275042 -0.275042)
							(end -0.3048 -0.2032)
						)
						(arc
							(start -0.3048 0.2032)
							(mid -0.275042 0.275042)
							(end -0.2032 0.3048)
						)
						(arc
							(start 0.2032 0.3048)
							(mid 0.275042 0.275042)
							(end 0.3048 0.2032)
						)
					)
					(width 0)
					(fill yes)
				)
			)
		)
	)
	(footprint ""
		(layer "F.Cu")
		(at 227.83165 -39.299896 90)
		(property "Reference" "R9936"
			(at 0 0 90)
			(layer "F.SilkS")
			(hide yes)
			(effects
				(font
					(size 1.27 1.27)
				)
			)
		)
		(property "Value" "4K7R2J-2-GP"
			(at 0.064008 -3.993896 90)
			(unlocked yes)
			(layer "F.Fab")
			(hide yes)
			(effects
				(font
					(size 1.016 1.016)
					(thickness 0.1524)
				)
			)
		)
		(property "Device Type" "R402H16"
			(at 0.064008 -5.517896 90)
			(unlocked yes)
			(layer "F.Fab")
			(hide yes)
			(effects
				(font
					(size 1.016 1.016)
					(thickness 0.1524)
				)
			)
		)
		(duplicate_pad_numbers_are_jumpers no)
		(fp_line
			(start 0.508 -0.9398)
			(end -0.508 -0.9398)
			(stroke
				(width 0.1524)
				(type default)
			)
			(layer "F.SilkS")
		)
		(fp_line
			(start -0.508 -0.9398)
			(end -0.508 0.9398)
			(stroke
				(width 0.1524)
				(type default)
			)
			(layer "F.SilkS")
		)
		(fp_rect
			(start -0.508 0.9398)
			(end 0.508 -0.9398)
			(stroke
				(width 0)
				(type default)
			)
			(fill no)
			(layer "F.CrtYd")
		)
		(fp_rect
			(start -0.508 0.9398)
			(end 0.508 -0.9398)
			(stroke
				(width 0)
				(type default)
			)
			(fill no)
			(layer "F.Fab")
		)
		(pad "1" smd custom
			(at 0 -0.4445 90)
			(size 0.1397 0.1397)
			(layers "F.Cu" "F.Mask" "F.Paste")
			(net "P3V3")
			(options
				(clearance outline)
				(anchor circle)
			)
			(primitives
				(gr_poly
					(pts
						(arc
							(start -0.1778 -0.2794)
							(mid -0.249642 -0.249642)
							(end -0.2794 -0.1778)
						)
						(arc
							(start -0.2794 0.1778)
							(mid -0.249642 0.249642)
							(end -0.1778 0.2794)
						)
						(arc
							(start 0.1778 0.2794)
							(mid 0.249642 0.249642)
							(end 0.2794 0.1778)
						)
						(arc
							(start 0.2794 -0.1778)
							(mid 0.249642 -0.249642)
							(end 0.1778 -0.2794)
						)
					)
					(width 0)
					(fill yes)
				)
			)
		)
		(pad "2" smd custom
			(at 0 0.4445 90)
			(size 0.1397 0.1397)
			(layers "F.Cu" "F.Mask" "F.Paste")
			(net "SSD_ACT_DR4_MOS_N")
			(options
				(clearance outline)
				(anchor circle)
			)
			(primitives
				(gr_poly
					(pts
						(arc
							(start -0.1778 -0.2794)
							(mid -0.249642 -0.249642)
							(end -0.2794 -0.1778)
						)
						(arc
							(start -0.2794 0.1778)
							(mid -0.249642 0.249642)
							(end -0.1778 0.2794)
						)
						(arc
							(start 0.1778 0.2794)
							(mid 0.249642 0.249642)
							(end 0.2794 0.1778)
						)
						(arc
							(start 0.2794 -0.1778)
							(mid 0.249642 -0.249642)
							(end 0.1778 -0.2794)
						)
					)
					(width 0)
					(fill yes)
				)
			)
		)
	)
	(footprint ""
		(layer "F.Cu")
		(at 16.204438 -362.581952 180)
		(property "Reference" "R9949"
			(at 0 0 180)
			(layer "F.SilkS")
			(hide yes)
			(effects
				(font
					(size 1.27 1.27)
				)
			)
		)
		(property "Value" "4K7R2J-2-GP"
			(at 0.064008 -3.993896 180)
			(unlocked yes)
			(layer "F.Fab")
			(hide yes)
			(effects
				(font
					(size 1.016 1.016)
					(thickness 0.1524)
				)
			)
		)
		(property "Device Type" "R402H16"
			(at 0.064008 -5.517896 180)
			(unlocked yes)
			(layer "F.Fab")
			(hide yes)
			(effects
				(font
					(size 1.016 1.016)
					(thickness 0.1524)
				)
			)
		)
		(duplicate_pad_numbers_are_jumpers no)
		(fp_line
			(start 0.508 -0.9398)
			(end -0.508 -0.9398)
			(stroke
				(width 0.1524)
				(type default)
			)
			(layer "F.SilkS")
		)
		(fp_line
			(start -0.508 -0.9398)
			(end -0.508 0.9398)
			(stroke
				(width 0.1524)
				(type default)
			)
			(layer "F.SilkS")
		)
		(fp_rect
			(start -0.508 0.9398)
			(end 0.508 -0.9398)
			(stroke
				(width 0)
				(type default)
			)
			(fill no)
			(layer "F.CrtYd")
		)
		(fp_rect
			(start -0.508 0.9398)
			(end 0.508 -0.9398)
			(stroke
				(width 0)
				(type default)
			)
			(fill no)
			(layer "F.Fab")
		)
		(pad "1" smd custom
			(at 0 -0.4445 180)
			(size 0.1397 0.1397)
			(layers "F.Cu" "F.Mask" "F.Paste")
			(net "P3V3")
			(options
				(clearance outline)
				(anchor circle)
			)
			(primitives
				(gr_poly
					(pts
						(arc
							(start -0.1778 -0.2794)
							(mid -0.249642 -0.249642)
							(end -0.2794 -0.1778)
						)
						(arc
							(start -0.2794 0.1778)
							(mid -0.249642 0.249642)
							(end -0.1778 0.2794)
						)
						(arc
							(start 0.1778 0.2794)
							(mid 0.249642 0.249642)
							(end 0.2794 0.1778)
						)
						(arc
							(start 0.2794 -0.1778)
							(mid 0.249642 -0.249642)
							(end 0.1778 -0.2794)
						)
					)
					(width 0)
					(fill yes)
				)
			)
		)
		(pad "2" smd custom
			(at 0 0.4445 180)
			(size 0.1397 0.1397)
			(layers "F.Cu" "F.Mask" "F.Paste")
			(net "ATTN_LED_DR11_MOS_N")
			(options
				(clearance outline)
				(anchor circle)
			)
			(primitives
				(gr_poly
					(pts
						(arc
							(start -0.1778 -0.2794)
							(mid -0.249642 -0.249642)
							(end -0.2794 -0.1778)
						)
						(arc
							(start -0.2794 0.1778)
							(mid -0.249642 0.249642)
							(end -0.1778 0.2794)
						)
						(arc
							(start 0.1778 0.2794)
							(mid 0.249642 0.249642)
							(end 0.2794 0.1778)
						)
						(arc
							(start 0.2794 -0.1778)
							(mid 0.249642 -0.249642)
							(end 0.1778 -0.2794)
						)
					)
					(width 0)
					(fill yes)
				)
			)
		)
	)
)
